FILE_TYPE = CONNECTIVITY;
{Allegro Design Entry HDL 16.6-p007 (v16-6-112F) 10/10/2012}
"PAGE_NUMBER" = 219;
0"NC";
1"PVDDQ_DEF\g";
2"GND\g";
3"GND\g";
4"P5V_STBY\g";
5"GND\g";
6"GND\g";
7"GND\g";
8"GND\g";
9"GND\g";
10"GND\g";
11"GND\g";
12"GND\g";
13"PVDDQ_DEF\g";
14"GND\g";
15"GND\g";
16"GND\g";
17"VR_FET_SW_P12V_STBY_PVDDQ_DEF\g";
18"GND\g";
19"VR_FET_SW_P12V_STBY_PVDDQ_DEF\g";
20"P5V_STBY\g";
21"VR_PVDDQ_DEF_PH2_VCIN";
22"ISENSE_PVDDQ_DEF_PH2_IMON";
23"VR_PVDDQ_DEF_PH2_PHASE";
24"VR_PVDDQ_DEF_PH1_VCIN";
25"TP_PVDDQ_DEF_PH1_GL_0";
26"TP_PVDDQ_DEF_PH1_GL_1";
27"TP_PVDDQ_DEF_PH2_GL_1";
28"TP_PVDDQ_DEF_PH2_GL_0";
29"NC_PVDDQ_DEF_PH2_P31";
30"VR_PVDDQ_DEF_PWM2";
31"NC_PVDDQ_DEF_PH1_P31";
32"UN$219$3D01R5F-GP$I126$2";
33"VR_PVDDQ_DEF_PWM1";
34"VR_PVDDQ_DEF_PH2_OCSET"VOLTAGE"3.6";
35"VR_PVDDQ_DEF_PH1_BOOT";
36"VR_PVDDQ_DEF_PH1_PHASE";
37"VR_PVDDQ_DEF_AIREF1";
38"VR_PVDDQ_DEF_PH1_BOOT_R";
39"VR_PVDDQ_DEF_PH2_BOOT";
40"VR_PVDDQ_DEF_PH2_BOOT_R";
41"A_TSENSE_PVDDQ_DEF";
42"UN$219$3D01R5F-GP$I123$2";
43"VR_PVDDQ_DEF_AIREF2";
44"VR_PVDDQ_DEF_PH1_SW";
45"VR_PVDDQ_DEF_PH1_OCSET"VOLTAGE"3.6";
46"A_TSENSE_PVDDQ_DEF";
47"ISENSE_PVDDQ_DEF_PH1_IMON";
48"VR_PVDDQ_DEF_PH2_SW";
%"PVDDQ_DEF"
"1","(4075,1875)","0","mstr_symbols","I1";
;
VOLTAGE"1.2V"
CDS_LIB"mstr_symbols"
BODY_TYPE"PLUMBING"
HDL_POWER"PVDDQ_DEF";
"G\NAC"1;
%"IR354XX"
"1","(1550,2075)","0","mstr_discrete","I106";
;
CDS_SEC"1"
CDS_LIB"mstr_discrete"
PACK_TYPE"SM"
SEC_TYPE"SM"
SEC"1"
CDS_LOCATION"EU7A1"
PART_NUMBER"H73688-001"
VALUE"IR35411"
LOCATION"EU7A1"
MATERIAL"IC"
NO_XNET_CONNECTION"1";
"TOUT_FLT"
$PN"36"46;
"NC"
$PN"31"31;
"OCSET"
$PN"37"45;
"IOUT"
$PN"38"47;
"SW"
$PN"10"44;
"BOOST"
$PN"33"38;
"REFIN"
$PN"39"37;
"PWM"
$PN"34"33;
"PHASE"
$PN"32"36;
"VIN<0>"
$PN"25"19;
"VCC"
$PN"3"24;
"VIN<1>"
$PN"30"19;
"EN"
$PN"35"4;
"VDRV"
$PN"4"4;
"VOS"
$PN"1"1;
"LGND"
$PN"2"11;
"PGND<1>"
$PN"7"11;
"PGND<2>"
$PN"40"11;
"PGND<0>"
$PN"5"11;
"GL<0>"
$PN"6"25;
"GL<1>"
$PN"41"26;
%"IR354XX"
"1","(1575,-50)","0","mstr_discrete","I107";
;
CDS_SEC"1"
PACK_TYPE"SM"
SEC_TYPE"SM"
SEC"1"
CDS_LOCATION"EU7A4"
CDS_LIB"mstr_discrete"
MATERIAL"IC"
VALUE"IR35411"
LOCATION"EU7A4"
NO_XNET_CONNECTION"1"
PART_NUMBER"H73688-001";
"TOUT_FLT"
$PN"36"41;
"NC"
$PN"31"29;
"OCSET"
$PN"37"34;
"IOUT"
$PN"38"22;
"SW"
$PN"10"48;
"BOOST"
$PN"33"40;
"REFIN"
$PN"39"43;
"PWM"
$PN"34"30;
"PHASE"
$PN"32"23;
"VIN<0>"
$PN"25"17;
"VCC"
$PN"3"21;
"VIN<1>"
$PN"30"17;
"EN"
$PN"35"20;
"VDRV"
$PN"4"20;
"VOS"
$PN"1"13;
"LGND"
$PN"2"16;
"PGND<1>"
$PN"7"16;
"PGND<2>"
$PN"40"16;
"PGND<0>"
$PN"5"16;
"GL<0>"
$PN"6"28;
"GL<1>"
$PN"41"27;
%"RES"
"2","(4375,2250)","0","mstr_discrete","I108";
;
CDS_LOCATION"R7A20"
CDS_SEC"1"
$SEC"1"
CDS_LIB"mstr_discrete"
PART_NUMBER"G21796-187"
VALUE"68.1K"
LOCATION"R7A20"
MATERIAL"EMPTY"
PACK_TYPE"0402"
WATTAGE"1/16W"
TOLERANCE"1%";
"A"
$PN"1"45;
"B"
$PN"2"2;
%"GND"
"1","(4375,1950)","0","mstr_symbols","I109";
;
HDL_POWER"GND"
VOLTAGE"0"
SIZE"1B"
CDS_LIB"mstr_symbols"
BODY_TYPE"PLUMBING"
BOM_COST"PROC_VRD_VCCIN_CPU0"
ROOM"PVCCIN_CPU0_PWR_VR";
"A\NAC"2;
%"RES"
"2","(4375,100)","0","mstr_discrete","I110";
;
CDS_LOCATION"R7A21"
CDS_SEC"1"
$SEC"1"
CDS_LIB"mstr_discrete"
MATERIAL"EMPTY"
LOCATION"R7A21"
VALUE"68.1K"
WATTAGE"1/16W"
TOLERANCE"1%"
PART_NUMBER"G21796-187"
PACK_TYPE"0402";
"A"
$PN"1"34;
"B"
$PN"2"3;
%"GND"
"1","(4375,-200)","0","mstr_symbols","I111";
;
HDL_POWER"GND"
VOLTAGE"0"
SIZE"1B"
CDS_LIB"mstr_symbols"
BODY_TYPE"PLUMBING"
BOM_COST"PROC_VRD_VCCIN_CPU0"
ROOM"PVCCIN_CPU0_PWR_VR";
"A\NAC"3;
%"P5V_STBY"
"1","(25,3100)","0","mstr_symbols","I112";
;
SIZE"1B"
CDS_LIB"mstr_symbols"
VOLTAGE"5.0V"
BODY_TYPE"PLUMBING"
HDL_POWER"P5V_STBY";
"G\NAC"4;
%"CAP_A"
"1","(875,-550)","0","dev_discrete","I113";
;
CDS_SEC"1"
$SEC"1"
CDS_LOCATION"CT46"
CDS_LIB"dev_discrete"
ROOM"PVCCIN_CPU0_PWR_VR"
VALUE"0.1UF"
TOLERANCE"10%"
VOLTAGE"16V"
PART_NUMBER"A36096-030"
PACK_TYPE"0402V"
MATERIAL"X7R"
LOCATION"CT46"
STATUS"NOPOP";
"B"
$PN"2"5;
"A"
$PN"1"43;
%"GND"
"1","(875,-825)","0","mstr_symbols","I114";
;
CDS_LIB"mstr_symbols"
BODY_TYPE"PLUMBING"
ROOM"PVCCIN_CPU0_PWR_VR"
BOM_COST"PROC_VRD_VCCIN_CPU0"
SIZE"1B"
VOLTAGE"0"
HDL_POWER"GND";
"A\NAC"5;
%"CAP_A"
"1","(825,1575)","0","dev_discrete","I116";
;
CDS_SEC"1"
$SEC"1"
CDS_LOCATION"CT45"
CDS_LIB"dev_discrete"
ROOM"PVCCIN_CPU0_PWR_VR"
STATUS"NOPOP"
PACK_TYPE"0402V"
PART_NUMBER"A36096-030"
LOCATION"CT45"
TOLERANCE"10%"
VOLTAGE"16V"
MATERIAL"X7R"
VALUE"0.1UF";
"B"
$PN"2"6;
"A"
$PN"1"37;
%"GND"
"1","(825,1325)","0","mstr_symbols","I117";
;
HDL_POWER"GND"
VOLTAGE"0"
SIZE"1B"
BOM_COST"PROC_VRD_VCCIN_CPU0"
ROOM"PVCCIN_CPU0_PWR_VR"
BODY_TYPE"PLUMBING"
CDS_LIB"mstr_symbols";
"A\NAC"6;
%"CAP"
"1","(2600,-25)","0","mstr_discrete","I119";
;
CDS_SEC"1"
$SEC"1"
CDS_LOCATION"CT48"
ROOM"VDDQ_KLM_PWR_VR"
CDS_LIB"mstr_discrete"
PART_NUMBER"A36096-046"
VALUE"1000PF"
STATUS"NOPOP"
LOCATION"CT48"
VOLTAGE"50V"
TOLERANCE"10%"
MATERIAL"X7R"
PACK_TYPE"0402LF";
"A"
$PN"1"41;
"B"
$PN"2"7;
%"GND"
"1","(2600,-225)","0","mstr_symbols","I120";
;
ROOM"VDDQ_KLM_PWR_VR"
VOLTAGE"0"
BODY_TYPE"PLUMBING"
SIZE"1B"
HDL_POWER"GND"
CDS_LIB"mstr_symbols";
"A\NAC"7;
%"SC2K2P50V3KX-GP"
"1","(2675,-525)","0","w_hdl","I121";
;
CDS_SEC"1"
$SEC"1"
CDS_LOCATION"CT47"
PART_NUMBER"78.22224.2BL"
PACK_TYPE"SMD-BCG6"
CDS_LIB"w_hdl"
CDS_LMAN_SYM_OUTLINE"-50,25,50,-25"
STATUS"NOPOP"
VALUE"SC2K2P50V3KX-GP"
LOCATION"CT47";
"2"
$PN"2"42;
"1"
$PN"1"48;
%"GND"
"1","(2675,-1100)","0","mstr_symbols","I122";
;
HDL_POWER"GND"
SIZE"1B"
VOLTAGE"0"
BODY_TYPE"PLUMBING"
BOM_COST"PROC_VRD_VCCIN_CPU0"
ROOM"PVCCIN_CPU0_PWR_VR"
CDS_LIB"mstr_symbols";
"A\NAC"8;
%"3D01R5F-GP"
"1","(2675,-850)","4","w_hdl","I123";
;
CDS_SEC"1"
$SEC"1"
CDS_LOCATION"RT32"
PACK_TYPE"SMD-RG5"
PART_NUMBER"64.3R015.16L"
CDS_LIB"w_hdl"
CDS_LMAN_SYM_OUTLINE"-50,75,50,-75"
VALUE"3D01R5F-GP"
LOCATION"RT32"
STATUS"NOPOP";
"2"
$PN"2"42;
"1"
$PN"1"8;
%"CAP"
"1","(2700,2075)","0","mstr_discrete","I124";
;
CDS_SEC"1"
$SEC"1"
CDS_LOCATION"CT43"
CDS_LIB"mstr_discrete"
ROOM"VDDQ_KLM_PWR_VR"
LOCATION"CT43"
STATUS"NOPOP"
PART_NUMBER"A36096-046"
MATERIAL"X7R"
TOLERANCE"10%"
VOLTAGE"50V"
VALUE"1000PF"
PACK_TYPE"0402LF";
"A"
$PN"1"46;
"B"
$PN"2"9;
%"GND"
"1","(2700,1875)","0","mstr_symbols","I125";
;
CDS_LIB"mstr_symbols"
ROOM"VDDQ_KLM_PWR_VR"
VOLTAGE"0"
BODY_TYPE"PLUMBING"
SIZE"1B"
HDL_POWER"GND";
"A\NAC"9;
%"3D01R5F-GP"
"1","(2800,1325)","4","w_hdl","I126";
;
CDS_SEC"1"
$SEC"1"
CDS_LOCATION"RT29"
PACK_TYPE"SMD-RG5"
PART_NUMBER"64.3R015.16L"
CDS_LIB"w_hdl"
CDS_LMAN_SYM_OUTLINE"-50,75,50,-75"
STATUS"NOPOP"
LOCATION"RT29"
VALUE"3D01R5F-GP";
"2"
$PN"2"32;
"1"
$PN"1"10;
%"SC2K2P50V3KX-GP"
"1","(2800,1625)","0","w_hdl","I127";
;
CDS_SEC"1"
$SEC"1"
CDS_LOCATION"CT44"
PACK_TYPE"SMD-BCG6"
PART_NUMBER"78.22224.2BL"
CDS_LMAN_SYM_OUTLINE"-50,25,50,-25"
CDS_LIB"w_hdl"
VALUE"SC2K2P50V3KX-GP"
STATUS"NOPOP"
LOCATION"CT44";
"2"
$PN"2"32;
"1"
$PN"1"44;
%"GND"
"1","(2800,1100)","0","mstr_symbols","I128";
;
HDL_POWER"GND"
SIZE"1B"
VOLTAGE"0"
BODY_TYPE"PLUMBING"
BOM_COST"PROC_VRD_VCCIN_CPU0"
ROOM"PVCCIN_CPU0_PWR_VR"
CDS_LIB"mstr_symbols";
"A\NAC"10;
%"RES"
"1","(-350,1850)","0","mstr_discrete","I129";
;
CDS_SEC"1"
$SEC"1"
CDS_LOCATION"RT30"
CDS_LIB"mstr_discrete"
ROOM"BMC_DEBUG_HEADER"
BOM_COST"DEBUG"
PACK_TYPE"0402"
PART_NUMBER"G21497-005"
LOCATION"RT30"
VALUE"0.0"
TOLERANCE"5%"
MATERIAL"CHIP"
WATTAGE"1/16W";
"B"
$PN"2"38;
"A"
$PN"1"35;
%"RES"
"1","(-100,-275)","0","mstr_discrete","I130";
;
CDS_SEC"1"
$SEC"1"
CDS_LOCATION"RT31"
BOM_COST"DEBUG"
ROOM"BMC_DEBUG_HEADER"
CDS_LIB"mstr_discrete"
WATTAGE"1/16W"
PACK_TYPE"0402"
MATERIAL"CHIP"
TOLERANCE"5%"
VALUE"0.0"
PART_NUMBER"G21497-005"
LOCATION"RT31";
"B"
$PN"2"40;
"A"
$PN"1"39;
%"GND"
"1","(2400,1325)","0","mstr_symbols","I19";
;
HDL_POWER"GND"
VOLTAGE"0"
CDS_LIB"mstr_symbols"
BODY_TYPE"PLUMBING"
SIZE"1B"
BOM_COST"PROC_VRD_VCCIN_CPU0"
ROOM"VDDQ_DEF_PWR_VR";
"A\NAC"11;
%"GND"
"1","(-2500,1950)","0","mstr_symbols","I35";
;
HDL_POWER"GND"
BOM_COST"PROC_VRD_VCCIN_CPU0"
ROOM"VDDQ_DEF_PWR_VR"
VOLTAGE"0"
CDS_LIB"mstr_symbols"
SIZE"1B"
BODY_TYPE"PLUMBING";
"A\NAC"12;
%"CAP"
"1","(-1300,1725)","2","mstr_discrete","I44";
;
ROOM"VDDQ_DEF_PWR_VR"
$SEC"1"
CDS_LOCATION"C7A12"
SPOF"TRUE"
CDS_SEC"1"
CDS_LIB"mstr_discrete"
VOLTAGE"16V"
VALUE"0.220UF"
LOCATION"C7A12"
TOLERANCE"10%"
MATERIAL"X7R"
PART_NUMBER"A36096-104"
PACK_TYPE"0402";
"A"
$PN"1"35;
"B"
$PN"2"36;
%"CAP"
"1","(-2500,2400)","0","mstr_discrete","I45";
;
CDS_SEC"1"
$SEC"1"
ROOM"VDDQ_DEF_PWR_VR"
CDS_LOCATION"C3L2"
CDS_LIB"mstr_discrete"
PART_NUMBER"C95333-007"
LOCATION"C3L2"
VALUE"10UF"
TOLERANCE"10%"
VOLTAGE"16V"
MATERIAL"X6S"
PACK_TYPE"0805";
"A"
$PN"1"19;
"B"
$PN"2"12;
%"CAP"
"1","(-2250,2375)","0","mstr_discrete","I46";
;
CDS_SEC"1"
$SEC"1"
ROOM"VDDQ_DEF_PWR_VR"
CDS_LOCATION"C3L4"
CDS_LIB"mstr_discrete"
PART_NUMBER"C95333-007"
LOCATION"C3L4"
VALUE"10UF"
TOLERANCE"10%"
VOLTAGE"16V"
PACK_TYPE"0805"
MATERIAL"X6S";
"A"
$PN"1"19;
"B"
$PN"2"12;
%"CAP"
"1","(-2000,2375)","0","mstr_discrete","I47";
;
CDS_SEC"1"
$SEC"1"
ROOM"VDDQ_DEF_PWR_VR"
CDS_LOCATION"C3L13"
CDS_LIB"mstr_discrete"
PART_NUMBER"C95333-007"
LOCATION"C3L13"
VALUE"10UF"
TOLERANCE"10%"
VOLTAGE"16V"
PACK_TYPE"0805"
MATERIAL"X6S";
"A"
$PN"1"19;
"B"
$PN"2"12;
%"CAP"
"1","(-1725,2375)","0","mstr_discrete","I48";
;
CDS_SEC"1"
$SEC"1"
ROOM"VDDQ_DEF_PWR_VR"
CDS_LOCATION"C7A11"
CDS_LIB"mstr_discrete"
PACK_TYPE"0402"
LOCATION"C7A11"
PART_NUMBER"D97712-011"
VALUE"1.0UF"
TOLERANCE"10%"
VOLTAGE"16V"
MATERIAL"X6S";
"A"
$PN"1"19;
"B"
$PN"2"12;
%"CAP"
"1","(-1200,2350)","0","mstr_discrete","I50";
;
CDS_SEC"1"
$SEC"1"
ROOM"VDDQ_DEF_PWR_VR"
CDS_LOCATION"C7A16"
CDS_LIB"mstr_discrete"
VOLTAGE"16V"
TOLERANCE"10%"
PART_NUMBER"D97712-011"
LOCATION"C7A16"
VALUE"1.0UF"
PACK_TYPE"0402"
MATERIAL"X6S";
"A"
$PN"1"24;
"B"
$PN"2"12;
%"CAP_A"
"1","(-1475,2375)","0","dev_discrete","I51";
;
$SEC"1"
CDS_SEC"1"
ROOM"VDDQ_DEF_PWR_VR"
CDS_LOCATION"C7A5"
CDS_LIB"dev_discrete"
LOCATION"C7A5"
PART_NUMBER"A36096-030"
VALUE"0.1UF"
PACK_TYPE"0402V"
TOLERANCE"10%"
VOLTAGE"16V"
MATERIAL"X7R";
"B"
$PN"2"12;
"A"
$PN"1"19;
%"RES"
"1","(-975,2950)","0","mstr_discrete","I52";
;
CDS_LIB"mstr_discrete"
CDS_SEC"1"
$SEC"1"
ROOM"VDDQ_DEF_PWR_VR"
CDS_LOCATION"R3L6"
MATERIAL"CHIP"
PACK_TYPE"0402"
LOCATION"R3L6"
PART_NUMBER"G21796-090"
TOLERANCE"1%"
WATTAGE"1/16W"
VALUE"1.0";
"B"
$PN"2"4;
"A"
$PN"1"24;
%"CAP_A"
"1","(-575,2375)","2","dev_discrete","I53";
;
$SEC"1"
CDS_SEC"1"
ROOM"VDDQ_DEF_PWR_VR"
CDS_LOCATION"C7A18"
CDS_LIB"dev_discrete"
TOLERANCE"10%"
VOLTAGE"6.3V"
MATERIAL"X6S"
LOCATION"C7A18"
PART_NUMBER"D97712-004"
VALUE"1.0UF"
PACK_TYPE"0402V";
"B"
$PN"2"12;
"A"
$PN"1"4;
%"CAP"
"1","(-475,2375)","0","mstr_discrete","I54";
;
$SEC"1"
CDS_SEC"1"
ROOM"VDDQ_DEF_PWR_VR"
CDS_LIB"mstr_discrete"
CDS_LOCATION"C7A17"
VALUE"0.22UF"
PART_NUMBER"A36096-155"
TOLERANCE"10%"
LOCATION"C7A17"
VOLTAGE"16V"
MATERIAL"X7R"
PACK_TYPE"0402";
"A"
$PN"1"4;
"B"
$PN"2"12;
%"INDUCTOR"
"1","(3400,1775)","0","mstr_discrete","I55";
;
ROOM"VDDQ_DEF_PWR_VR"
CDS_LOCATION"L7A1"
$SEC"1"
CDS_SEC"1"
CDS_LIB"mstr_discrete"
PART_NUMBER"D92183-034"
PACK_TYPE"SM"
VALUE"0.12UH"
LOCATION"L7A1"
MATERIAL"IND";
"INA\NAC"
$PN"1"44;
"INB\NAC"
$PN"2"1;
%"PVDDQ_DEF"
"1","(4100,-250)","0","mstr_symbols","I64";
;
BOM_COST"PROC_SOCKET "
CDS_LIB"mstr_symbols"
ROOM"VDDQ_DEF_PWR_VR"
HDL_POWER"PVDDQ_DEF"
VOLTAGE"1.2V"
BODY_TYPE"PLUMBING";
"G\NAC"13;
%"INDUCTOR"
"1","(3175,-350)","0","mstr_discrete","I65";
;
CDS_SEC"1"
SEC_TYPE"SM"
SEC"1"
ROOM"VDDQ_DEF_PWR_VR"
CDS_LIB"mstr_discrete"
CDS_LOCATION"L7A3"
VALUE"0.12UH"
LOCATION"L7A3"
MATERIAL"IND"
PART_NUMBER"D92183-034"
PACK_TYPE"SM";
"INA\NAC"
$PN"1"48;
"INB\NAC"
$PN"2"13;
%"CAP"
"1","(4100,-550)","0","mstr_discrete","I68";
;
CDS_SEC"1"
SEC_TYPE"0805LF"
SEC"1"
BOM_COST"PROC_VRD_VCCIN_CPU0"
ROOM"VDDQ_DEF_PWR_VR"
CDS_LOCATION"C6A4"
VOLTAGE"4V"
CDS_LIB"mstr_discrete"
LOCATION"C6A4"
VALUE"22UF"
PART_NUMBER"C95333-002"
TOLERANCE"20%"
PACK_TYPE"0805LF"
MATERIAL"X6S";
"A"
$PN"1"13;
"B"
$PN"2"14;
%"GND"
"1","(4100,-775)","0","mstr_symbols","I69";
;
HDL_POWER"GND"
VOLTAGE"0"
CDS_LIB"mstr_symbols"
SIZE"1B"
BOM_COST"PROC_VRD_VCCIN_CPU0"
BODY_TYPE"PLUMBING"
ROOM"VDDQ_DEF_PWR_VR";
"A\NAC"14;
%"GND"
"1","(4075,1350)","0","mstr_symbols","I7";
;
SIZE"1B"
HDL_POWER"GND"
BODY_TYPE"PLUMBING"
CDS_LIB"mstr_symbols"
VOLTAGE"0"
BOM_COST"PROC_VRD_VCCIN_CPU0"
ROOM"VDDQ_DEF_PWR_VR";
"A\NAC"15;
%"GND"
"1","(2425,-800)","0","mstr_symbols","I70";
;
HDL_POWER"GND"
CDS_LIB"mstr_symbols"
VOLTAGE"0"
SIZE"1B"
BODY_TYPE"PLUMBING"
BOM_COST"PROC_VRD_VCCIN_CPU0"
ROOM"VDDQ_DEF_PWR_VR";
"A\NAC"16;
%"CAP"
"1","(-550,250)","0","mstr_discrete","I72";
;
CDS_SEC"1"
SEC_TYPE"0402"
SEC"1"
CDS_LOCATION"C7A25"
ROOM"VDDQ_DEF_PWR_VR"
CDS_LIB"mstr_discrete"
PART_NUMBER"A36096-155"
LOCATION"C7A25"
VALUE"0.22UF"
TOLERANCE"10%"
PACK_TYPE"0402"
VOLTAGE"16V"
MATERIAL"X7R";
"A"
$PN"1"20;
"B"
$PN"2"18;
%"CAP_A"
"1","(-725,250)","2","dev_discrete","I73";
;
SEC_TYPE"0402V"
CDS_LIB"dev_discrete"
CDS_SEC"1"
CDS_LOCATION"C7A26"
SEC"1"
ROOM"VDDQ_DEF_PWR_VR"
LOCATION"C7A26"
VALUE"1.0UF"
TOLERANCE"10%"
PACK_TYPE"0402V"
VOLTAGE"6.3V"
MATERIAL"X6S"
PART_NUMBER"D97712-004";
"B"
$PN"2"18;
"A"
$PN"1"20;
%"CAP"
"1","(-1000,-450)","2","mstr_discrete","I75";
;
CDS_LIB"mstr_discrete"
SPOF"TRUE"
CDS_SEC"1"
$SEC"1"
CDS_LOCATION"C7A22"
ROOM"VDDQ_DEF_PWR_VR"
VALUE"0.220UF"
LOCATION"C7A22"
PART_NUMBER"A36096-104"
TOLERANCE"10%"
PACK_TYPE"0402"
VOLTAGE"16V"
MATERIAL"X7R";
"A"
$PN"1"39;
"B"
$PN"2"23;
%"RES"
"1","(-1100,775)","0","mstr_discrete","I76";
;
CDS_SEC"1"
SEC_TYPE"0402"
SEC"1"
CDS_LIB"mstr_discrete"
CDS_LOCATION"R3L8"
ROOM"VDDQ_DEF_PWR_VR"
PART_NUMBER"G21796-090"
PACK_TYPE"0402"
MATERIAL"CHIP"
LOCATION"R3L8"
TOLERANCE"1%"
WATTAGE"1/16W"
VALUE"1.0";
"B"
$PN"2"20;
"A"
$PN"1"21;
%"CAP"
"1","(-1400,150)","0","mstr_discrete","I77";
;
CDS_SEC"1"
SEC_TYPE"0402"
SEC"1"
ROOM"VDDQ_DEF_PWR_VR"
CDS_LOCATION"C7A24"
CDS_LIB"mstr_discrete"
TOLERANCE"10%"
VALUE"1.0UF"
LOCATION"C7A24"
VOLTAGE"16V"
MATERIAL"X6S"
PART_NUMBER"D97712-011"
PACK_TYPE"0402";
"A"
$PN"1"21;
"B"
$PN"2"18;
%"CAP_A"
"1","(-1675,125)","0","dev_discrete","I78";
;
SEC"1"
SEC_TYPE"0402V"
CDS_SEC"1"
ROOM"VDDQ_DEF_PWR_VR"
CDS_LIB"dev_discrete"
CDS_LOCATION"C7A20"
LOCATION"C7A20"
VALUE"0.1UF"
VOLTAGE"16V"
TOLERANCE"10%"
MATERIAL"X7R"
PART_NUMBER"A36096-030"
PACK_TYPE"0402V";
"B"
$PN"2"18;
"A"
$PN"1"17;
%"CAP"
"1","(-1925,125)","0","mstr_discrete","I79";
;
CDS_SEC"1"
ROOM"VDDQ_DEF_PWR_VR"
SEC"1"
SEC_TYPE"0402"
CDS_LOCATION"C7A21"
CDS_LIB"mstr_discrete"
LOCATION"C7A21"
VALUE"1.0UF"
TOLERANCE"10%"
VOLTAGE"16V"
MATERIAL"X6S"
PART_NUMBER"D97712-011"
PACK_TYPE"0402";
"A"
$PN"1"17;
"B"
$PN"2"18;
%"CAP"
"1","(-2175,125)","0","mstr_discrete","I80";
;
CDS_SEC"1"
ROOM"VDDQ_DEF_PWR_VR"
SEC"1"
SEC_TYPE"0805"
CDS_LOCATION"C3L17"
CDS_LIB"mstr_discrete"
LOCATION"C3L17"
VALUE"10UF"
TOLERANCE"10%"
VOLTAGE"16V"
MATERIAL"X6S"
PART_NUMBER"C95333-007"
PACK_TYPE"0805";
"A"
$PN"1"17;
"B"
$PN"2"18;
%"CAP"
"1","(-2425,125)","0","mstr_discrete","I81";
;
CDS_SEC"1"
ROOM"VDDQ_DEF_PWR_VR"
SEC"1"
SEC_TYPE"0805"
CDS_LOCATION"C3L16"
CDS_LIB"mstr_discrete"
LOCATION"C3L16"
VALUE"10UF"
TOLERANCE"10%"
VOLTAGE"16V"
MATERIAL"X6S"
PART_NUMBER"C95333-007"
PACK_TYPE"0805";
"A"
$PN"1"17;
"B"
$PN"2"18;
%"VCC_CORE"
"1","(-2675,575)","0","mstr_symbols","I83";
;
CDS_LIB"mstr_symbols"
HDL_POWER"VR_FET_SW_P12V_STBY_PVDDQ_DEF";
"A"17;
%"CAP"
"1","(-2675,125)","0","mstr_discrete","I84";
;
CDS_SEC"1"
SEC"1"
SEC_TYPE"0805"
ROOM"VDDQ_DEF_PWR_VR"
CDS_LIB"mstr_discrete"
CDS_LOCATION"C3L15"
LOCATION"C3L15"
VALUE"10UF"
TOLERANCE"10%"
VOLTAGE"16V"
MATERIAL"X6S"
PART_NUMBER"C95333-007"
PACK_TYPE"0805";
"A"
$PN"1"17;
"B"
$PN"2"18;
%"GND"
"1","(-2675,-175)","0","mstr_symbols","I85";
;
HDL_POWER"GND"
CDS_LIB"mstr_symbols"
SIZE"1B"
VOLTAGE"0"
BODY_TYPE"PLUMBING"
BOM_COST"PROC_VRD_VCCIN_CPU0"
ROOM"VDDQ_DEF_PWR_VR";
"A\NAC"18;
%"VCC_CORE"
"1","(-2500,2625)","0","mstr_symbols","I86";
;
CDS_LIB"mstr_symbols"
HDL_POWER"VR_FET_SW_P12V_STBY_PVDDQ_DEF";
"A"19;
%"CAP"
"1","(4075,1575)","0","mstr_discrete","I87";
;
ROOM"VDDQ_DEF_PWR_VR"
CDS_LOCATION"C6A1"
$SEC"1"
CDS_SEC"1"
BOM_COST"PROC_VRD_VCCIN_CPU0"
VOLTAGE"4V"
CDS_LIB"mstr_discrete"
VALUE"22UF"
LOCATION"C6A1"
TOLERANCE"20%"
PART_NUMBER"C95333-002"
PACK_TYPE"0805LF"
MATERIAL"X6S";
"A"
$PN"1"1;
"B"
$PN"2"15;
%"P5V_STBY"
"1","(100,900)","0","mstr_symbols","I89";
;
SIZE"1B"
CDS_LIB"mstr_symbols"
BODY_TYPE"PLUMBING"
VOLTAGE"5.0V"
HDL_POWER"P5V_STBY";
"G\NAC"20;
END.
